FILE_TYPE = MULTI_PHYS_TABLE;

PART 'NUT'
CLASS=IO

{========================================================================================}
:CLS_PN             = JEDEC_TYPE                        | ALT_SYMBOLS                                                          | DESCRIPTION                                                     | CPN_STATUS ;
{========================================================================================}
 'G340-10124-01'    = 'P_NUT_166CT244CB198_H084'        | '(P_NUT_166CT244CB198_H084,P_NUT_166CT244CB276,P_NUT_166CT244CB315)' | 'HDW, NUT, SMLS0-M3-2ET, SMT'                                   | 'NFND'    
 'G200-10580-01'    = 'P_NUT_223C335'                   | '(P_NUT_223C335)'                                                    | 'CON,STAND ALONE GUIDED PIN KIT, 5.65MM PTH'                    | ''        
 'G340-10209-01'    = 'P_NUT_166CT244CB198_H359'        | '(P_NUT_166CT244CB198_H359)'                                         | 'HDWR,M3 NUT,L9,CARBON STEEL'                                   | ''        
 'G340-10230-01'    = 'P_NUT_166CT244CB198_H474'        | '(P_NUT_166CT244CB198_H474)'                                         | 'HDW, NUT, M3-12, SMT'                                          | ''        
 'G340-10271-01'    = 'P_NUT_166CT272CB198'             | '(P_NUT_166CT272CB198)'                                              | 'HDWR,M2.5 NUT,L16.27,STEEL'                                    | ''        
 'G340-10292-01'    = 'P_NUT_147C244'                   | '(P_NUT_147C244)'                                                    | 'HDW,STANDOFF,M2X0.4-6H,SMT'                                    | ''        
 'G340-10332-01'    = 'P_NUT_166CT244CB198_H517'        | '(P_NUT_166CT244CB198_H517)'                                         | 'HDW,STANDOFF,M3X0.5,L13MM,SMT'                                 | ''        
 'R0996-E1003-01'   = 'P_NUT_147CT244CB178_H262'        | '(P_NUT_147CT244CB178_H262)'                                         | 'MECH, LTE CARD POLE H6.55'                                     | ''        
 'R0996-E0006-01'   = 'P_NUT_147CT244CB178_H194'        | '(P_NUT_147CT244CB178_H194)'                                         | 'MECH, M.2 CARD POLE H4.1'                                      | ''        
 'G340-10352-01'    = 'P_NUT_166CT244CB198_V2_H202'     | '(P_NUT_166CT244CB198_V2_H202)'                                      | 'HDW, NUT, M3-5, SMT'                                           | ''        
 'G340-10363-01'    = 'P_NUT_165CT295CB197'             | '(P_NUT_165CT295CB197)'                                              | 'HDW,SMT STANDOFF M3'                                           | ''        
 'G340-10362-01'    = 'P_NUT_098CT165OB177X492'         | '(P_NUT_098CT165OB177X492)'                                          | 'HDW,HEX NUT,THREAD .060-80 (#0-80),HOLE DIA 0.098INCH,SMT'     | ''        
 'G340-10364-01'    = 'P_NUT_166CT244CB198_H320'        | '(P_NUT_166CT244CB198_H320)'                                         | 'HDW,SMT STANDOFF,M2.5L8MM'                                     | ''        
 'G340-10361-01'    = 'P_NUT_166CT244CB198_H111'        | '(P_NUT_166CT244CB198_H111)'                                         | 'HDW,STANDOFF,M3X0.5-6H,SMT'                                    | ''        
 'G340-10365-01'    = 'P_NUT_147CT244CB178_V1'          | '(P_NUT_147CT244CB178_V1)'                                           | 'HDW,STANDOFF,M3.6 5.4MM,L1.53 4.14MM'                          | ''        
 'G340-10367-01'    = 'P_NUT_147CT244CB178_H096'        | '(P_NUT_147CT244CB178_H096)'                                         | 'HDW,STANDOFF,M2,HEIGHT 2.3MM'                                  | ''        
 'G340-10370-01'    = 'P_NUT_166CT244CB198_H320_3D1'    | '(P_NUT_166CT244CB198_H320_3D1)'                                     | 'HDW,NUT,SMTSO-M3-8ET,SMT'                                      | ''        
 'G340-10373-01'    = 'P_NUT_165C295_H335'              | '(P_NUT_165C295_H335)'                                               | 'MECH,SMT STANDOFF M3L8'                                        | ''        
 'G340-10374-01'    = 'P_NUT_165CT256CB197'             | '(P_NUT_165CT256CB197)'                                              | 'MECH,SMT STANDOFF M3L6.6'                                      | ''        
 'R1063-E5001-01'   = 'P_NUT_147CT244CB178_V2'          | '(P_NUT_147CT244CB178_V2)'                                           | 'MECH, SMT STANDOFF, M2 L6.56, CUSTOM'                          | ''        
 'G340-10377-01'    = 'P_NUT_166CT244CB198_H261'        | '(P_NUT_166CT244CB198_H261)'                                         | 'HDW,NUT,SMT_NUT_L6-5,SMT'                                      | ''        
 'G340-10378-01'    = 'P_NUT_166CT244CB198_H320_3D2'    | '(P_NUT_166CT244CB198_H320_3D2)'                                     | 'HDW,NUT,SMT_NUT_L8,SMT'                                        | ''        
 'G340-10382-01'    = 'P_NUT_166CT244CB198_V2'          | '(P_NUT_166CT244CB198_V2)'                                           | 'HDW,SMT NUT,M3,H1.5MM'                                         | ''        
 'G340-10385-01'    = 'P_NUT_165CT276CB197_V1'          | '(P_NUT_165CT276CB197_V1)'                                           | 'NUT,REELFAST SURFACE MOUNT STANDOFFS,3EB03-01,ES-31310-11622A' | ''        
 'G340-10061-01'    = 'P_NUT_166CT244CB198_H241'        | '(P_NUT_166CT244CB198_H241)'                                         | 'REELFAST SURFACE MOUNT STANDOFFS - TYPE SMTSO -M3XL6MM METRIC' | ''        
 'G340-10333-01'    = 'P_NUT_166CT244CB198_H163'        | '(P_NUT_166CT244CB198_H163)'                                         | 'HDW,NUT, SMTSO-M3-4ET,SMT'                                     | ''        
 'G340-10390-01'    = 'P_NUT_118C197'                   | '(P_NUT_118C197)'                                                    | 'HDW,SMT NUT AND STANDOFF M2XL2.5'                              | ''        
 'G340-10391-01'    = 'P_NUT_147CT244CB178_V3'          | '(P_NUT_147CT244CB178_V3_CST)'                                           | 'HDW,NUT,SMT,M2*0.4'                                            | ''        
 'G340-10392-01'    = 'P_NUT_163CT244CB315'             | '(P_NUT_163CT244CB315)'                                              | 'MECH,SMT NUT M3L12'                                            | ''        
 'G340-10393-01'    = 'P_NUT_166CT244CB198_H281'        | '(P_NUT_166CT244CB198_H281)'                                         | 'HDW,SMT SO STANDOFF'                                           | ''        
 'G340-10394-01'    = 'P_NUT_171CT244CB276'             | '(P_NUT_171CT244CB276)'                                              | 'HDW, SMT SO PAD NUT, M3, 1.2MM STEP, 2MM HIGH'                 | ''        
 'G340-10395-01'    = 'P_NUT_165CT335CB197'             | '(P_NUT_165CT335CB197)'                                              | 'MECH,SMT NUT M3L3'                                             | ''        
 'G340-10397-01'    = 'P_NUT_193CT276B227'              | '(P_NUT_193CT276B227)'                                               | 'STAND OFF,THREADED,M3 X 0.5 H5-7,SMT'                          | ''        
 'G340-10161-01'    = 'P_NUT_166CT244CB198_H084'        | '(P_NUT_166CT244CB198_H084)'                                         | 'PENN ENGINEERING & MANUFACTURING CORP'                         | ''        
 'G340-10401-01'    = 'P_NUT_146CT236CB177'             | '(P_NUT_146CT236CB177)'                                              | 'HDW,NUT,SMT,M3*2.3'                                            | ''        
 'G340-10402-01'    = 'P_NUT_166CT244CB198_H067'        | '(P_NUT_166CT244CB198_H067)'                                         | 'HDW,SMT SO STANDOFF, #4-40'                                    | ''        
 'G340-10403-01'    = 'P_NUT_166CT244CB198_H241'        | '(P_NUT_166CT244CB198_H241)'                                         | 'HDW,SMT SO STANDOFF, M2.5-6MM'                                 | ''        
 'G340-10399-01'    = 'P_NUT_166CT244CB198_V2_H202_ME'  | '(P_NUT_166CT244CB198_V2_H202_ME)'                                   | 'HDW,SMT SO STANDOFF, 3MM L=5MM'                                | ''        
 'G340-10404-01'    = 'P_NUT_250CT369CB287'             | '(P_NUT_250CT369CB287)'                                              | 'HDW,SMT SO STANDOFF, M4-2MM'                                   | ''        
 'G340-10156-01'    = 'P_NUT_166CT244CB198_H084'        | '(P_NUT_166CT244CB198_H084)'                                         | 'MECH,SMT NUT AND STANDOFF,M2.5X0.45'                           | ''        
 'G340-10405-01'    = 'P_NUT_166CT244CB198_H084'        | '(P_NUT_166CT244CB198_H084)'                                         | 'HDW, SMT SO PAD NUT, M2.5X0.45, 1.4MM STEP, 2MM HIGH'          | ''        
 'R3006-E1082-01'   = 'P_NUT_165CT276CB197_V1_H138'     | '(P_NUT_165CT276CB197_V1_H138)'                                      | 'MECH,SMT NUT,M3XL3'                                            | ''        
 'G340-10411-01'    = 'P_NUT_147CT244CB178_V2_H264'     | '(P_NUT_147CT244CB178_V2_H264)'                                      | 'HDW,STANDOFF,M2,HEIGHT 6.6MM'                                  | ''        
 'G340-10201-01'    = 'P_NUT_252CT472CB295'             | '(P_NUT_252CT472CB295)'                                              | 'STAND OFF, DIAMETER 7.2 X 8.1'                                 | ''        
 'R1102-E8001-01'   = 'P_NUT_166CT244CB198_H098'        | '(P_NUT_166CT244CB198_H098)'                                         | 'HDW,NUT,SMT_NUT_L2.35,SMT'                                     | ''        
 'R3106-E0006-01'   = 'P_NUT_166CT244CB198_H220'        | '(P_NUT_166CT244CB198_H220)'                                         | 'MECH,BMC NUT M2.5'                                             | ''        
 'G340-10413-01'    = 'P_NUT_165CT394CB197P'            | '(P_NUT_165CT394CB197P)'                                             | 'HDW,NUT,82-159-22-016-01-RL,M3X0.5 THREAD,SMT'                 | ''        
 'G724-03001-01'    = 'P_NUT_220CT362CB255'             | '(P_NUT_220CT362CB255)'                                              | 'SCREW,SMT THUMBSCREW,M3'                                       | ''        
 'G340-10414-01'    = 'P_NUT_244C413P_SPECIAL'          | '(P_NUT_244C413P_SPECIAL)'                                           | 'HDW,SCREW,EQ-31712-11K01A,M5X0.8 THREAD,16.8MM LENGTH'         | ''        
 'G340-10415-01'    = 'P_NUT_166CT244CB198_H220'        | '(P_NUT_166CT244CB198_H220)'                                         | 'MECH,BMC NUT M3'                                               | ''        
 'G340-10418-01'    = 'P_NUT_165CT276CB197_V1_H791'     | '(P_NUT_165CT276CB197_V1_H791)'                                      | 'MECH,SMT NUT M3L20'                                            | ''        
 'G340-10419-01'    = 'P_NUT_224CT374CB259'             | '(P_NUT_224CT374CB259)'                                              | 'HDW,NUT,M3X0.5 THREAD,SMT'                                     | ''        
 'G340-10420-01'    = 'P_NUT_166CT244CB198_V1'          | '(P_NUT_166CT244CB198_V1)'                                           | 'HDW,NUT,YSMTSO-73861-ET,M2.5X0.45 THREAD,SMT'                  | ''        
 'G722-00003-01'    = 'P_NUT_248CT400CB284P'            | '(P_NUT_248CT400CB284P)'                                             | 'SCREW,4C CAPTIVE FASTENER M3.5 THREAD,SMT'                     | ''        
 'G340-10421-01'    = 'P_NUT_166CT244CB198_V1_H140'     | '(P_NUT_166CT244CB198_V1_H140)'                                      | 'HDW,THRU-THREADED,M3,H3.5MM,SMT'                               | ''        
 'G340-10426-01'    = 'P_NUT_166CT244CB198_H163_3D1'    | '(P_NUT_166CT244CB198_H163_3D1)'                                     | 'HDW,SMT STANDOFF,M2.5L4MM'                                     | ''        
 'G340-10427-01'    = 'P_NUT_166CT244CB198_V2_H202_ME1' | '(P_NUT_166CT244CB198_V2_H202_ME1)'                                  | 'HDW,SMT STANDOFF,M2.5L5MM'                                     | ''        
 'G340-10429-01'    = 'P_NUT_193CT276B227_V1'           | '(P_NUT_193CT276B227_V1)'                                            | 'SCREW,WING HEAD CAPTIVE FASTENER M3 THREAD,L 22.2MM'           | ''        
 'R3116-E0002-01'   = 'P_NUT_166CT244CB198_H607'        | '(P_NUT_166CT244CB276_V2,P_NUT_166C244_V1)'                          | 'MECH,PSU BP NUT2 M3X0.5 FAB4'                                  | ''        
 'R3116-E0001-01'   = 'P_NUT_166CT244CB198_V3'          | '(P_NUT_166CT244CB276_V1,P_NUT_166C244)'                             | 'MECH,PSU BP NUT1 M3X0.5 FAB4'                                  | ''        
 'G340-10430-01'    = 'P_NUT_220CT354CB255'             | '(P_NUT_220CT354CB255)'                                              | 'MECH,THUMB SCREW'                                              | ''        
 'G724-03002-01'    = 'P_NUT_220CT362CB255_V1'          | '(P_NUT_220CT362CB255_V1)'                                           | 'SCREW,SMT THUMBSCREW,M3,COOL GRAY 5C'                          | ''        
 'R3235-E0001-01'   = 'P_NUT_147CT244CB137'             | '(P_NUT_147CT244CB137)'                                              | 'MECH,NUT,M2X0.4XL2,THRED,SMT'                                  | ''        
 'G340-10431-01'    = 'P_NUT_143CT197CB174P'            | '(P_NUT_143CT197CB174P)'                                             | 'HDW,NUT,M2.5,SMT'                                              | ''        
 'G340-10161-02'    = 'P_NUT_166CT244CB198_H084_3D1'    | '(P_NUT_166CT244CB198_H084_3D1)'                                     | 'HDW,STAND OFF,THREADED,M3X0.5X3.53,SMT'                        | ''        
 'A200-00029-FB'    = 'P_NUT_079C100'                   | '(P_NUT_079C100)'                                                    | 'CON,1P,RECEPTACLE WITH OFP SOLDER BARRIER,DIA 0.940MM-1.092MM' | ''        
 'G340-10437-01'    = 'P_NUT_166CT244CB198_V1_H380'     | '(P_NUT_166CT244CB198_V1_H380)'                                      | 'HDW,SMT STANDOFF,#4-40,L.375'                                  | ''        

END_PART

END.

